(kicad_sch
	(version 20250114)
	(generator "eeschema")
	(generator_version "9.0")
	(paper "A3")
	(title_block
		(title "COM Express 7 Baseboard")
		(date "2025-02-04")
		(rev "1.1.2")
		(company "Antmicro Ltd")
		(comment 1 "www.antmicro.com")
	)
	(bus_alias "SDIO"
		(members "DAT0" "DAT1" "DAT2" "DAT3" "CLK" "CMD")
	)
	(text "SD card connector"
		(exclude_from_sim no)
		(at 209.55 110.744 0)
		(effects
			(font
				(size 2 2)
				(thickness 0.8)
				(bold yes)
			)
			(justify left bottom)
		)
	)
	(junction
		(at 203.2 168.91)
		(diameter 0)
		(color 0 0 0 0)
	)
	(junction
		(at 222.25 125.73)
		(diameter 0)
		(color 0 0 0 0)
	)
	(junction
		(at 213.36 147.32)
		(diameter 0)
		(color 0 0 0 0)
	)
	(junction
		(at 220.98 149.86)
		(diameter 0)
		(color 0 0 0 0)
	)
	(junction
		(at 228.6 157.48)
		(diameter 0)
		(color 0 0 0 0)
	)
	(junction
		(at 213.36 125.73)
		(diameter 0)
		(color 0 0 0 0)
	)
	(junction
		(at 226.06 154.94)
		(diameter 0)
		(color 0 0 0 0)
	)
	(junction
		(at 210.82 144.78)
		(diameter 0)
		(color 0 0 0 0)
	)
	(junction
		(at 215.9 157.48)
		(diameter 0)
		(color 0 0 0 0)
	)
	(junction
		(at 223.52 152.4)
		(diameter 0)
		(color 0 0 0 0)
	)
	(junction
		(at 208.28 142.24)
		(diameter 0)
		(color 0 0 0 0)
	)
	(no_connect
		(at 205.74 170.18)
	)
	(bus_entry
		(at 185.42 146.05)
		(size 1.27 1.27)
		(stroke
			(width 0)
			(type default)
		)
	)
	(bus_entry
		(at 185.42 151.13)
		(size 1.27 1.27)
		(stroke
			(width 0)
			(type default)
		)
	)
	(bus_entry
		(at 185.42 153.67)
		(size 1.27 1.27)
		(stroke
			(width 0)
			(type default)
		)
	)
	(bus_entry
		(at 185.42 143.51)
		(size 1.27 1.27)
		(stroke
			(width 0)
			(type default)
		)
	)
	(bus_entry
		(at 185.42 140.97)
		(size 1.27 1.27)
		(stroke
			(width 0)
			(type default)
		)
	)
	(bus_entry
		(at 185.42 148.59)
		(size 1.27 1.27)
		(stroke
			(width 0)
			(type default)
		)
	)
	(wire
		(pts
			(xy 213.36 147.32) (xy 213.36 170.18)
		)
		(stroke
			(width 0)
			(type default)
		)
	)
	(wire
		(pts
			(xy 186.69 144.78) (xy 210.82 144.78)
		)
		(stroke
			(width 0)
			(type default)
		)
	)
	(wire
		(pts
			(xy 228.6 157.48) (xy 238.76 157.48)
		)
		(stroke
			(width 0)
			(type default)
		)
	)
	(wire
		(pts
			(xy 213.36 125.73) (xy 213.36 128.27)
		)
		(stroke
			(width 0)
			(type default)
		)
	)
	(wire
		(pts
			(xy 238.76 137.16) (xy 236.22 137.16)
		)
		(stroke
			(width 0)
			(type default)
		)
	)
	(wire
		(pts
			(xy 237.49 163.83) (xy 238.76 163.83)
		)
		(stroke
			(width 0)
			(type default)
		)
	)
	(wire
		(pts
			(xy 226.06 154.94) (xy 226.06 170.18)
		)
		(stroke
			(width 0)
			(type default)
		)
	)
	(wire
		(pts
			(xy 203.2 168.91) (xy 218.44 168.91)
		)
		(stroke
			(width 0)
			(type default)
		)
	)
	(wire
		(pts
			(xy 180.34 157.48) (xy 215.9 157.48)
		)
		(stroke
			(width 0)
			(type default)
		)
	)
	(wire
		(pts
			(xy 222.25 125.73) (xy 236.22 125.73)
		)
		(stroke
			(width 0)
			(type default)
		)
	)
	(wire
		(pts
			(xy 236.22 137.16) (xy 236.22 125.73)
		)
		(stroke
			(width 0)
			(type default)
		)
	)
	(bus
		(pts
			(xy 180.34 139.7) (xy 184.15 139.7)
		)
		(stroke
			(width 0)
			(type default)
		)
	)
	(bus
		(pts
			(xy 185.42 151.13) (xy 185.42 153.67)
		)
		(stroke
			(width 0)
			(type default)
		)
	)
	(bus
		(pts
			(xy 185.42 143.51) (xy 185.42 146.05)
		)
		(stroke
			(width 0)
			(type default)
		)
	)
	(wire
		(pts
			(xy 186.69 152.4) (xy 223.52 152.4)
		)
		(stroke
			(width 0)
			(type default)
		)
	)
	(wire
		(pts
			(xy 203.2 168.91) (xy 203.2 170.18)
		)
		(stroke
			(width 0)
			(type default)
		)
	)
	(wire
		(pts
			(xy 210.82 144.78) (xy 210.82 170.18)
		)
		(stroke
			(width 0)
			(type default)
		)
	)
	(wire
		(pts
			(xy 215.9 139.7) (xy 215.9 157.48)
		)
		(stroke
			(width 0)
			(type default)
		)
	)
	(wire
		(pts
			(xy 208.28 142.24) (xy 208.28 170.18)
		)
		(stroke
			(width 0)
			(type default)
		)
	)
	(wire
		(pts
			(xy 198.12 168.91) (xy 198.12 170.18)
		)
		(stroke
			(width 0)
			(type default)
		)
	)
	(wire
		(pts
			(xy 237.49 166.37) (xy 237.49 163.83)
		)
		(stroke
			(width 0)
			(type default)
		)
	)
	(bus
		(pts
			(xy 185.42 146.05) (xy 185.42 148.59)
		)
		(stroke
			(width 0)
			(type default)
		)
	)
	(wire
		(pts
			(xy 199.39 139.7) (xy 203.2 139.7)
		)
		(stroke
			(width 0)
			(type default)
		)
	)
	(wire
		(pts
			(xy 220.98 149.86) (xy 220.98 170.18)
		)
		(stroke
			(width 0)
			(type default)
		)
	)
	(wire
		(pts
			(xy 186.69 147.32) (xy 213.36 147.32)
		)
		(stroke
			(width 0)
			(type default)
		)
	)
	(bus
		(pts
			(xy 185.42 140.97) (xy 184.15 139.7)
		)
		(stroke
			(width 0)
			(type default)
		)
	)
	(wire
		(pts
			(xy 198.12 168.91) (xy 203.2 168.91)
		)
		(stroke
			(width 0)
			(type default)
		)
	)
	(wire
		(pts
			(xy 279.4 163.83) (xy 283.21 163.83)
		)
		(stroke
			(width 0)
			(type default)
		)
	)
	(wire
		(pts
			(xy 283.21 163.83) (xy 283.21 166.37)
		)
		(stroke
			(width 0)
			(type default)
		)
	)
	(wire
		(pts
			(xy 223.52 152.4) (xy 223.52 170.18)
		)
		(stroke
			(width 0)
			(type default)
		)
	)
	(wire
		(pts
			(xy 210.82 144.78) (xy 238.76 144.78)
		)
		(stroke
			(width 0)
			(type default)
		)
	)
	(wire
		(pts
			(xy 222.25 125.73) (xy 222.25 129.54)
		)
		(stroke
			(width 0)
			(type default)
		)
	)
	(wire
		(pts
			(xy 220.98 149.86) (xy 238.76 149.86)
		)
		(stroke
			(width 0)
			(type default)
		)
	)
	(wire
		(pts
			(xy 186.69 142.24) (xy 208.28 142.24)
		)
		(stroke
			(width 0)
			(type default)
		)
	)
	(wire
		(pts
			(xy 213.36 134.62) (xy 213.36 133.35)
		)
		(stroke
			(width 0)
			(type default)
		)
	)
	(wire
		(pts
			(xy 186.69 154.94) (xy 226.06 154.94)
		)
		(stroke
			(width 0)
			(type default)
		)
	)
	(wire
		(pts
			(xy 226.06 154.94) (xy 238.76 154.94)
		)
		(stroke
			(width 0)
			(type default)
		)
	)
	(wire
		(pts
			(xy 228.6 157.48) (xy 228.6 170.18)
		)
		(stroke
			(width 0)
			(type default)
		)
	)
	(wire
		(pts
			(xy 199.39 138.43) (xy 199.39 139.7)
		)
		(stroke
			(width 0)
			(type default)
		)
	)
	(bus
		(pts
			(xy 185.42 140.97) (xy 185.42 143.51)
		)
		(stroke
			(width 0)
			(type default)
		)
	)
	(bus
		(pts
			(xy 185.42 148.59) (xy 185.42 151.13)
		)
		(stroke
			(width 0)
			(type default)
		)
	)
	(wire
		(pts
			(xy 208.28 139.7) (xy 215.9 139.7)
		)
		(stroke
			(width 0)
			(type default)
		)
	)
	(wire
		(pts
			(xy 223.52 152.4) (xy 238.76 152.4)
		)
		(stroke
			(width 0)
			(type default)
		)
	)
	(wire
		(pts
			(xy 213.36 147.32) (xy 238.76 147.32)
		)
		(stroke
			(width 0)
			(type default)
		)
	)
	(wire
		(pts
			(xy 215.9 157.48) (xy 228.6 157.48)
		)
		(stroke
			(width 0)
			(type default)
		)
	)
	(wire
		(pts
			(xy 186.69 149.86) (xy 220.98 149.86)
		)
		(stroke
			(width 0)
			(type default)
		)
	)
	(wire
		(pts
			(xy 218.44 170.18) (xy 218.44 168.91)
		)
		(stroke
			(width 0)
			(type default)
		)
	)
	(wire
		(pts
			(xy 208.28 142.24) (xy 238.76 142.24)
		)
		(stroke
			(width 0)
			(type default)
		)
	)
	(wire
		(pts
			(xy 213.36 125.73) (xy 222.25 125.73)
		)
		(stroke
			(width 0)
			(type default)
		)
	)
	(wire
		(pts
			(xy 213.36 124.46) (xy 213.36 125.73)
		)
		(stroke
			(width 0)
			(type default)
		)
	)
	(label "SDIO.DAT0"
		(at 198.12 152.4 180)
		(effects
			(font
				(size 1.27 1.27)
			)
			(justify right bottom)
		)
	)
	(label "SDIO.DAT1"
		(at 198.12 154.94 180)
		(effects
			(font
				(size 1.27 1.27)
			)
			(justify right bottom)
		)
	)
	(label "SDIO.CLK"
		(at 198.12 149.86 180)
		(effects
			(font
				(size 1.27 1.27)
			)
			(justify right bottom)
		)
	)
	(label "SDIO.CMD"
		(at 198.12 147.32 180)
		(effects
			(font
				(size 1.27 1.27)
			)
			(justify right bottom)
		)
	)
	(label "SDIO.DAT2"
		(at 198.12 142.24 180)
		(effects
			(font
				(size 1.27 1.27)
			)
			(justify right bottom)
		)
	)
	(label "SDIO.DAT3"
		(at 198.12 144.78 180)
		(effects
			(font
				(size 1.27 1.27)
			)
			(justify right bottom)
		)
	)
	(hierarchical_label "CD_SW"
		(shape output)
		(at 180.34 157.48 180)
		(effects
			(font
				(size 1.27 1.27)
			)
			(justify right)
		)
	)
	(hierarchical_label "SDIO{SDIO}"
		(shape input)
		(at 180.34 139.7 180)
		(effects
			(font
				(size 1.27 1.27)
			)
			(justify right)
		)
	)
	(symbol
		(lib_id "antmicroResistors0402:R_10k_0402")
		(at 208.28 139.7 180)
		(unit 1)
		(exclude_from_sim no)
		(in_bom yes)
		(on_board yes)
		(dnp no)
		(property "Reference" "R321"
			(at 205.74 134.62 0)
			(effects
				(font
					(size 1.27 1.27)
					(thickness 0.15)
				)
			)
		)
		(property "Value" "R_10k_0402"
			(at 187.96 127 0)
			(effects
				(font
					(size 1.27 1.27)
					(thickness 0.15)
				)
				(justify left bottom)
				(hide yes)
			)
		)
		(property "Footprint" "antmicro-footprints:R_0402_1005Metric"
			(at 187.96 124.46 0)
			(effects
				(font
					(size 1.27 1.27)
					(thickness 0.15)
				)
				(justify left bottom)
				(hide yes)
			)
		)
		(property "Datasheet" "https://www.bourns.com/docs/product-datasheets/cr.pdf"
			(at 187.96 121.92 0)
			(effects
				(font
					(size 1.27 1.27)
					(thickness 0.15)
				)
				(justify left bottom)
				(hide yes)
			)
		)
		(property "Description" ""
			(at 208.28 139.7 0)
			(effects
				(font
					(size 1.27 1.27)
				)
				(hide yes)
			)
		)
		(property "MPN" "CR0402-FX-1002GLF"
			(at 187.96 119.38 0)
			(effects
				(font
					(size 1.27 1.27)
					(thickness 0.15)
				)
				(justify left bottom)
				(hide yes)
			)
		)
		(property "Manufacturer" "Bourns"
			(at 187.96 116.84 0)
			(effects
				(font
					(size 1.27 1.27)
					(thickness 0.15)
				)
				(justify left bottom)
				(hide yes)
			)
		)
		(property "License" "Apache-2.0"
			(at 187.96 114.3 0)
			(effects
				(font
					(size 1.27 1.27)
					(thickness 0.15)
				)
				(justify left bottom)
				(hide yes)
			)
		)
		(property "Author" "Antmicro"
			(at 187.96 111.76 0)
			(effects
				(font
					(size 1.27 1.27)
					(thickness 0.15)
				)
				(justify left bottom)
				(hide yes)
			)
		)
		(property "Val" "10k"
			(at 205.74 137.16 0)
			(effects
				(font
					(size 1.27 1.27)
					(thickness 0.15)
				)
			)
		)
		(property "Tolerance" "1%"
			(at 187.96 129.54 0)
			(effects
				(font
					(size 1.27 1.27)
				)
				(justify left bottom)
				(hide yes)
			)
		)
		(property "Public" "False"
			(at 187.96 109.22 0)
			(effects
				(font
					(size 1.27 1.27)
				)
				(justify left bottom)
				(hide yes)
			)
		)
		(pin "2"
		)
		(pin "1"
		)
		(instances
			(project "com-express-7-baseboard"
				(path ""
					(reference "R321")
					(unit 1)
				)
			)
		)
	)
	(symbol
		(lib_id "antmicropower:+3V3")
		(at 213.36 124.46 0)
		(unit 1)
		(exclude_from_sim no)
		(in_bom yes)
		(on_board yes)
		(dnp no)
		(property "Reference" "#PWR0432"
			(at 228.6 124.46 0)
			(effects
				(font
					(size 1.27 1.27)
					(thickness 0.15)
				)
				(justify left bottom)
				(hide yes)
			)
		)
		(property "Value" "+3V3"
			(at 213.36 120.65 0)
			(effects
				(font
					(size 1.27 1.27)
					(thickness 0.15)
				)
			)
		)
		(property "Footprint" ""
			(at 228.6 132.08 0)
			(effects
				(font
					(size 1.27 1.27)
					(thickness 0.15)
				)
				(justify left bottom)
				(hide yes)
			)
		)
		(property "Datasheet" ""
			(at 228.6 134.62 0)
			(effects
				(font
					(size 1.27 1.27)
					(thickness 0.15)
				)
				(justify left bottom)
				(hide yes)
			)
		)
		(property "Description" ""
			(at 213.36 124.46 0)
			(effects
				(font
					(size 1.27 1.27)
				)
				(hide yes)
			)
		)
		(property "Author" "Antmicro"
			(at 228.6 127 0)
			(effects
				(font
					(size 1.27 1.27)
					(thickness 0.15)
				)
				(justify left bottom)
				(hide yes)
			)
		)
		(property "License" "Apache-2.0"
			(at 228.6 129.54 0)
			(effects
				(font
					(size 1.27 1.27)
					(thickness 0.15)
				)
				(justify left bottom)
				(hide yes)
			)
		)
		(pin "1"
		)
		(instances
			(project "com-express-7-baseboard"
				(path ""
					(reference "#PWR0432")
					(unit 1)
				)
			)
		)
	)
	(symbol
		(lib_id "antmicroMemoryConnectorsPCCardSockets:MicroSD_693071020811")
		(at 238.76 137.16 0)
		(unit 1)
		(exclude_from_sim no)
		(in_bom yes)
		(on_board yes)
		(dnp no)
		(property "Reference" "J15"
			(at 260.35 128.27 0)
			(effects
				(font
					(size 1.27 1.27)
					(thickness 0.15)
				)
			)
		)
		(property "Value" "MicroSD_693071020811"
			(at 260.985 130.81 0)
			(effects
				(font
					(size 1.27 1.27)
					(thickness 0.15)
				)
				(hide yes)
			)
		)
		(property "Footprint" "antmicro-footprints:MicroSD_Wurth_693071020811"
			(at 294.64 144.78 0)
			(effects
				(font
					(size 1.27 1.27)
					(thickness 0.15)
				)
				(justify left bottom)
				(hide yes)
			)
		)
		(property "Datasheet" "https://www.we-online.com/catalog/datasheet/693071020811.pdf"
			(at 294.64 147.32 0)
			(effects
				(font
					(size 1.27 1.27)
					(thickness 0.15)
				)
				(justify left bottom)
				(hide yes)
			)
		)
		(property "Description" ""
			(at 238.76 137.16 0)
			(effects
				(font
					(size 1.27 1.27)
				)
				(hide yes)
			)
		)
		(property "Manufacturer" "Würth Elektronik"
			(at 294.64 149.86 0)
			(effects
				(font
					(size 1.27 1.27)
					(thickness 0.15)
				)
				(justify left bottom)
				(hide yes)
			)
		)
		(property "MPN" "693071020811"
			(at 252.73 132.08 0)
			(effects
				(font
					(size 1.27 1.27)
					(thickness 0.15)
				)
				(justify left bottom)
			)
		)
		(property "Author" "Antmicro"
			(at 294.64 154.94 0)
			(effects
				(font
					(size 1.27 1.27)
					(thickness 0.15)
				)
				(justify left bottom)
				(hide yes)
			)
		)
		(property "License" "Apache-2.0"
			(at 294.64 157.48 0)
			(effects
				(font
					(size 1.27 1.27)
					(thickness 0.15)
				)
				(justify left bottom)
				(hide yes)
			)
		)
		(pin "5"
		)
		(pin "7"
		)
		(pin "6"
		)
		(pin "8"
		)
		(pin "9"
		)
		(pin "SH"
		)
		(pin "1"
		)
		(pin "2"
		)
		(pin "4"
		)
		(pin "3"
		)
		(instances
			(project "com-express-7-baseboard"
				(path ""
					(reference "J15")
					(unit 1)
				)
			)
		)
	)
	(symbol
		(lib_id "antmicropower:GND")
		(at 237.49 166.37 0)
		(unit 1)
		(exclude_from_sim no)
		(in_bom yes)
		(on_board yes)
		(dnp no)
		(property "Reference" "#PWR0434"
			(at 246.38 168.91 0)
			(effects
				(font
					(size 1.27 1.27)
					(thickness 0.15)
				)
				(justify left bottom)
				(hide yes)
			)
		)
		(property "Value" "GND"
			(at 237.49 170.18 0)
			(effects
				(font
					(size 1.27 1.27)
					(thickness 0.15)
				)
			)
		)
		(property "Footprint" ""
			(at 246.38 173.99 0)
			(effects
				(font
					(size 1.27 1.27)
					(thickness 0.15)
				)
				(justify left bottom)
				(hide yes)
			)
		)
		(property "Datasheet" ""
			(at 246.38 179.07 0)
			(effects
				(font
					(size 1.27 1.27)
					(thickness 0.15)
				)
				(justify left bottom)
				(hide yes)
			)
		)
		(property "Description" ""
			(at 237.49 166.37 0)
			(effects
				(font
					(size 1.27 1.27)
				)
				(hide yes)
			)
		)
		(property "Author" "Antmicro"
			(at 246.38 173.99 0)
			(effects
				(font
					(size 1.27 1.27)
					(thickness 0.15)
				)
				(justify left bottom)
				(hide yes)
			)
		)
		(property "License" "Apache-2.0"
			(at 246.38 176.53 0)
			(effects
				(font
					(size 1.27 1.27)
					(thickness 0.15)
				)
				(justify left bottom)
				(hide yes)
			)
		)
		(pin "1"
		)
		(instances
			(project "com-express-7-baseboard"
				(path ""
					(reference "#PWR0434")
					(unit 1)
				)
			)
		)
	)
	(symbol
		(lib_id "antmicroTVSDiodes:PESD5Z5_0F")
		(at 222.25 129.54 90)
		(mirror x)
		(unit 1)
		(exclude_from_sim no)
		(in_bom yes)
		(on_board yes)
		(dnp no)
		(property "Reference" "D29"
			(at 224.79 133.35 90)
			(effects
				(font
					(size 1.27 1.27)
					(thickness 0.15)
				)
				(justify right)
			)
		)
		(property "Value" "PESD5Z5_0F"
			(at 224.79 132.3976 90)
			(effects
				(font
					(size 1.27 1.27)
					(thickness 0.15)
				)
				(justify right)
				(hide yes)
			)
		)
		(property "Footprint" "antmicro-footprints:SOD-523"
			(at 227.33 144.78 0)
			(effects
				(font
					(size 1.27 1.27)
					(thickness 0.15)
				)
				(justify left bottom)
				(hide yes)
			)
		)
		(property "Datasheet" "https://assets.nexperia.com/documents/data-sheet/PESD5Z5_0.pdf"
			(at 229.87 144.78 0)
			(effects
				(font
					(size 1.27 1.27)
					(thickness 0.15)
				)
				(justify left bottom)
				(hide yes)
			)
		)
		(property "Description" ""
			(at 222.25 129.54 0)
			(effects
				(font
					(size 1.27 1.27)
				)
				(hide yes)
			)
		)
		(property "Manufacturer" "Nexperia"
			(at 232.41 144.78 0)
			(effects
				(font
					(size 1.27 1.27)
					(thickness 0.15)
				)
				(justify left bottom)
				(hide yes)
			)
		)
		(property "MPN" "PESD5Z5.0F"
			(at 224.79 130.81 90)
			(effects
				(font
					(size 1.27 1.27)
					(thickness 0.15)
				)
				(justify right)
			)
		)
		(property "Author" "Antmicro"
			(at 237.49 144.78 0)
			(effects
				(font
					(size 1.27 1.27)
					(thickness 0.15)
				)
				(justify left bottom)
				(hide yes)
			)
		)
		(property "License" "Apache-2.0"
			(at 240.03 144.78 0)
			(effects
				(font
					(size 1.27 1.27)
					(thickness 0.15)
				)
				(justify left bottom)
				(hide yes)
			)
		)
		(property "Public" "False"
			(at 240.03 149.86 0)
			(effects
				(font
					(size 1.27 1.27)
				)
				(justify left bottom)
				(hide yes)
			)
		)
		(pin "1"
		)
		(pin "2"
		)
		(instances
			(project "com-express-7-baseboard"
				(path ""
					(reference "D29")
					(unit 1)
				)
			)
		)
	)
	(symbol
		(lib_id "antmicropower:GND")
		(at 213.36 134.62 0)
		(unit 1)
		(exclude_from_sim no)
		(in_bom yes)
		(on_board yes)
		(dnp no)
		(property "Reference" "#PWR0433"
			(at 222.25 137.16 0)
			(effects
				(font
					(size 1.27 1.27)
					(thickness 0.15)
				)
				(justify left bottom)
				(hide yes)
			)
		)
		(property "Value" "GND"
			(at 213.36 138.43 0)
			(effects
				(font
					(size 1.27 1.27)
					(thickness 0.15)
				)
			)
		)
		(property "Footprint" ""
			(at 222.25 142.24 0)
			(effects
				(font
					(size 1.27 1.27)
					(thickness 0.15)
				)
				(justify left bottom)
				(hide yes)
			)
		)
		(property "Datasheet" ""
			(at 222.25 147.32 0)
			(effects
				(font
					(size 1.27 1.27)
					(thickness 0.15)
				)
				(justify left bottom)
				(hide yes)
			)
		)
		(property "Description" ""
			(at 213.36 134.62 0)
			(effects
				(font
					(size 1.27 1.27)
				)
				(hide yes)
			)
		)
		(property "Author" "Antmicro"
			(at 222.25 142.24 0)
			(effects
				(font
					(size 1.27 1.27)
					(thickness 0.15)
				)
				(justify left bottom)
				(hide yes)
			)
		)
		(property "License" "Apache-2.0"
			(at 222.25 144.78 0)
			(effects
				(font
					(size 1.27 1.27)
					(thickness 0.15)
				)
				(justify left bottom)
				(hide yes)
			)
		)
		(pin "1"
		)
		(instances
			(project "com-express-7-baseboard"
				(path ""
					(reference "#PWR0433")
					(unit 1)
				)
			)
		)
	)
	(symbol
		(lib_id "antmicropower:GND")
		(at 222.25 134.62 0)
		(mirror y)
		(unit 1)
		(exclude_from_sim no)
		(in_bom yes)
		(on_board yes)
		(dnp no)
		(property "Reference" "#PWR0264"
			(at 213.36 137.16 0)
			(effects
				(font
					(size 1.27 1.27)
					(thickness 0.15)
				)
				(justify left bottom)
				(hide yes)
			)
		)
		(property "Value" "GND"
			(at 222.25 138.43 0)
			(effects
				(font
					(size 1.27 1.27)
					(thickness 0.15)
				)
			)
		)
		(property "Footprint" ""
			(at 213.36 142.24 0)
			(effects
				(font
					(size 1.27 1.27)
					(thickness 0.15)
				)
				(justify left bottom)
				(hide yes)
			)
		)
		(property "Datasheet" ""
			(at 213.36 147.32 0)
			(effects
				(font
					(size 1.27 1.27)
					(thickness 0.15)
				)
				(justify left bottom)
				(hide yes)
			)
		)
		(property "Description" ""
			(at 222.25 134.62 0)
			(effects
				(font
					(size 1.27 1.27)
				)
				(hide yes)
			)
		)
		(property "Author" "Antmicro"
			(at 213.36 142.24 0)
			(effects
				(font
					(size 1.27 1.27)
					(thickness 0.15)
				)
				(justify left bottom)
				(hide yes)
			)
		)
		(property "License" "Apache-2.0"
			(at 213.36 144.78 0)
			(effects
				(font
					(size 1.27 1.27)
					(thickness 0.15)
				)
				(justify left bottom)
				(hide yes)
			)
		)
		(pin "1"
		)
		(instances
			(project "com-express-7-baseboard"
				(path ""
					(reference "#PWR0264")
					(unit 1)
				)
			)
		)
	)
	(symbol
		(lib_id "antmicropower:GND")
		(at 198.12 170.18 0)
		(unit 1)
		(exclude_from_sim no)
		(in_bom yes)
		(on_board yes)
		(dnp no)
		(property "Reference" "#PWR0429"
			(at 207.01 172.72 0)
			(effects
				(font
					(size 1.27 1.27)
					(thickness 0.15)
				)
				(justify left bottom)
				(hide yes)
			)
		)
		(property "Value" "GND"
			(at 198.12 173.99 0)
			(effects
				(font
					(size 1.27 1.27)
					(thickness 0.15)
				)
			)
		)
		(property "Footprint" ""
			(at 207.01 177.8 0)
			(effects
				(font
					(size 1.27 1.27)
					(thickness 0.15)
				)
				(justify left bottom)
				(hide yes)
			)
		)
		(property "Datasheet" ""
			(at 207.01 182.88 0)
			(effects
				(font
					(size 1.27 1.27)
					(thickness 0.15)
				)
				(justify left bottom)
				(hide yes)
			)
		)
		(property "Description" ""
			(at 198.12 170.18 0)
			(effects
				(font
					(size 1.27 1.27)
				)
				(hide yes)
			)
		)
		(property "Author" "Antmicro"
			(at 207.01 177.8 0)
			(effects
				(font
					(size 1.27 1.27)
					(thickness 0.15)
				)
				(justify left bottom)
				(hide yes)
			)
		)
		(property "License" "Apache-2.0"
			(at 207.01 180.34 0)
			(effects
				(font
					(size 1.27 1.27)
					(thickness 0.15)
				)
				(justify left bottom)
				(hide yes)
			)
		)
		(pin "1"
		)
		(instances
			(project "com-express-7-baseboard"
				(path ""
					(reference "#PWR0429")
					(unit 1)
				)
			)
		)
	)
	(symbol
		(lib_id "antmicropower:GND")
		(at 283.21 166.37 0)
		(unit 1)
		(exclude_from_sim no)
		(in_bom yes)
		(on_board yes)
		(dnp no)
		(property "Reference" "#PWR0435"
			(at 292.1 168.91 0)
			(effects
				(font
					(size 1.27 1.27)
					(thickness 0.15)
				)
				(justify left bottom)
				(hide yes)
			)
		)
		(property "Value" "GND"
			(at 283.21 170.18 0)
			(effects
				(font
					(size 1.27 1.27)
					(thickness 0.15)
				)
			)
		)
		(property "Footprint" ""
			(at 292.1 173.99 0)
			(effects
				(font
					(size 1.27 1.27)
					(thickness 0.15)
				)
				(justify left bottom)
				(hide yes)
			)
		)
		(property "Datasheet" ""
			(at 292.1 179.07 0)
			(effects
				(font
					(size 1.27 1.27)
					(thickness 0.15)
				)
				(justify left bottom)
				(hide yes)
			)
		)
		(property "Description" ""
			(at 283.21 166.37 0)
			(effects
				(font
					(size 1.27 1.27)
				)
				(hide yes)
			)
		)
		(property "Author" "Antmicro"
			(at 292.1 173.99 0)
			(effects
				(font
					(size 1.27 1.27)
					(thickness 0.15)
				)
				(justify left bottom)
				(hide yes)
			)
		)
		(property "License" "Apache-2.0"
			(at 292.1 176.53 0)
			(effects
				(font
					(size 1.27 1.27)
					(thickness 0.15)
				)
				(justify left bottom)
				(hide yes)
			)
		)
		(pin "1"
		)
		(instances
			(project "com-express-7-baseboard"
				(path ""
					(reference "#PWR0435")
					(unit 1)
				)
			)
		)
	)
	(symbol
		(lib_id "antmicropower:+3V3")
		(at 199.39 138.43 0)
		(unit 1)
		(exclude_from_sim no)
		(in_bom yes)
		(on_board yes)
		(dnp no)
		(property "Reference" "#PWR0431"
			(at 214.63 138.43 0)
			(effects
				(font
					(size 1.27 1.27)
					(thickness 0.15)
				)
				(justify left bottom)
				(hide yes)
			)
		)
		(property "Value" "+3V3"
			(at 199.39 134.62 0)
			(effects
				(font
					(size 1.27 1.27)
					(thickness 0.15)
				)
			)
		)
		(property "Footprint" ""
			(at 214.63 146.05 0)
			(effects
				(font
					(size 1.27 1.27)
					(thickness 0.15)
				)
				(justify left bottom)
				(hide yes)
			)
		)
		(property "Datasheet" ""
			(at 214.63 148.59 0)
			(effects
				(font
					(size 1.27 1.27)
					(thickness 0.15)
				)
				(justify left bottom)
				(hide yes)
			)
		)
		(property "Description" ""
			(at 199.39 138.43 0)
			(effects
				(font
					(size 1.27 1.27)
				)
				(hide yes)
			)
		)
		(property "Author" "Antmicro"
			(at 214.63 140.97 0)
			(effects
				(font
					(size 1.27 1.27)
					(thickness 0.15)
				)
				(justify left bottom)
				(hide yes)
			)
		)
		(property "License" "Apache-2.0"
			(at 214.63 143.51 0)
			(effects
				(font
					(size 1.27 1.27)
					(thickness 0.15)
				)
				(justify left bottom)
				(hide yes)
			)
		)
		(pin "1"
		)
		(instances
			(project "com-express-7-baseboard"
				(path ""
					(reference "#PWR0431")
					(unit 1)
				)
			)
		)
	)
	(symbol
		(lib_id "antmicroTVSDiodes:ESD204DQAR")
		(at 213.36 170.18 270)
		(unit 1)
		(exclude_from_sim no)
		(in_bom yes)
		(on_board yes)
		(dnp no)
		(property "Reference" "U46"
			(at 201.93 181.61 90)
			(effects
				(font
					(size 1.27 1.27)
				)
				(justify left bottom)
			)
		)
		(property "Value" "ESD204DQAR"
			(at 198.12 181.61 90)
			(effects
				(font
					(size 1.27 1.27)
					(thickness 0.15)
				)
				(justify left bottom)
				(hide yes)
			)
		)
		(property "Footprint" "antmicro-footprints:USON-10_2.5x1mm_P0.5mm"
			(at 208.28 194.31 0)
			(effects
				(font
					(size 1.27 1.27)
					(thickness 0.15)
				)
				(justify left bottom)
				(hide yes)
			)
		)
		(property "Datasheet" "https://www.ti.com/lit/ds/symlink/esd204.pdf?ts=1706004844383&ref_url=https%253A%252F%252Fwww.ti.com%252Finterface%252Fdiodes%252Fesd-protection-diodes%252Fproducts.html"
			(at 205.74 194.31 0)
			(effects
				(font
					(size 1.27 1.27)
					(thickness 0.15)
				)
				(justify left bottom)
				(hide yes)
			)
		)
		(property "Description" ""
			(at 213.36 170.18 0)
			(effects
				(font
					(size 1.27 1.27)
				)
				(hide yes)
			)
		)
		(property "Manufacturer" "Texas Instruments"
			(at 203.2 194.31 0)
			(effects
				(font
					(size 1.27 1.27)
					(thickness 0.15)
				)
				(justify left bottom)
				(hide yes)
			)
		)
		(property "MPN" "ESD204DQAR"
			(at 201.93 184.15 90)
			(effects
				(font
					(size 1.27 1.27)
					(thickness 0.15)
				)
				(justify left bottom)
			)
		)
		(property "Author" "Antmicro"
			(at 198.12 194.31 0)
			(effects
				(font
					(size 1.27 1.27)
					(thickness 0.15)
				)
				(justify left bottom)
				(hide yes)
			)
		)
		(property "License" "Apache-2.0"
			(at 195.58 194.31 0)
			(effects
				(font
					(size 1.27 1.27)
					(thickness 0.15)
				)
				(justify left bottom)
				(hide yes)
			)
		)
		(pin "1"
		)
		(pin "10"
		)
		(pin "2"
		)
		(pin "3"
		)
		(pin "4"
		)
		(pin "5"
		)
		(pin "6"
		)
		(pin "7"
		)
		(pin "8"
		)
		(pin "9"
		)
		(instances
			(project "com-express-7-baseboard"
				(path ""
					(reference "U46")
					(unit 1)
				)
			)
		)
	)
	(symbol
		(lib_id "antmicroCapacitors0402:C_100n_0402")
		(at 213.36 133.35 90)
		(unit 1)
		(exclude_from_sim no)
		(in_bom yes)
		(on_board yes)
		(dnp no)
		(fields_autoplaced yes)
		(property "Reference" "C202"
			(at 215.9 129.5336 90)
			(effects
				(font
					(size 1.27 1.27)
					(thickness 0.15)
				)
				(justify right)
			)
		)
		(property "Value" "C_100n_0402"
			(at 223.52 113.03 0)
			(effects
				(font
					(size 1.27 1.27)
					(thickness 0.15)
				)
				(justify left bottom)
				(hide yes)
			)
		)
		(property "Footprint" "antmicro-footprints:C_0402_1005Metric"
			(at 226.06 113.03 0)
			(effects
				(font
					(size 1.27 1.27)
					(thickness 0.15)
				)
				(justify left bottom)
				(hide yes)
			)
		)
		(property "Datasheet" "https://www.murata.com/products/productdetail?partno=GRM155R61H104KE14%23"
			(at 228.6 113.03 0)
			(effects
				(font
					(size 1.27 1.27)
					(thickness 0.15)
				)
				(justify left bottom)
				(hide yes)
			)
		)
		(property "Description" ""
			(at 213.36 133.35 0)
			(effects
				(font
					(size 1.27 1.27)
				)
				(hide yes)
			)
		)
		(property "MPN" "GRM155R61H104KE14D"
			(at 231.14 113.03 0)
			(effects
				(font
					(size 1.27 1.27)
					(thickness 0.15)
				)
				(justify left bottom)
				(hide yes)
			)
		)
		(property "Manufacturer" "Murata"
			(at 233.68 113.03 0)
			(effects
				(font
					(size 1.27 1.27)
					(thickness 0.15)
				)
				(justify left bottom)
				(hide yes)
			)
		)
		(property "License" "Apache-2.0"
			(at 236.22 113.03 0)
			(effects
				(font
					(size 1.27 1.27)
					(thickness 0.15)
				)
				(justify left bottom)
				(hide yes)
			)
		)
		(property "Author" "Antmicro"
			(at 238.76 113.03 0)
			(effects
				(font
					(size 1.27 1.27)
					(thickness 0.15)
				)
				(justify left bottom)
				(hide yes)
			)
		)
		(property "Val" "100n"
			(at 215.9 132.0736 90)
			(effects
				(font
					(size 1.27 1.27)
					(thickness 0.15)
				)
				(justify right)
			)
		)
		(property "Voltage" "50V"
			(at 241.3 113.03 0)
			(effects
				(font
					(size 1.27 1.27)
				)
				(justify left bottom)
				(hide yes)
			)
		)
		(property "Dielectric" "X5R"
			(at 243.84 113.03 0)
			(effects
				(font
					(size 1.27 1.27)
				)
				(justify left bottom)
				(hide yes)
			)
		)
		(property "Public" "False"
			(at 246.38 113.03 0)
			(effects
				(font
					(size 1.27 1.27)
				)
				(justify left bottom)
				(hide yes)
			)
		)
		(pin "2"
		)
		(pin "1"
		)
		(instances
			(project "com-express-7-baseboard"
				(path ""
					(reference "C202")
					(unit 1)
				)
			)
		)
	)
	(symbol
		(lib_id "antmicroTVSDiodes:ESD204DQAR")
		(at 228.6 170.18 270)
		(unit 1)
		(exclude_from_sim no)
		(in_bom yes)
		(on_board yes)
		(dnp no)
		(property "Reference" "U47"
			(at 217.17 181.61 90)
			(effects
				(font
					(size 1.27 1.27)
				)
				(justify left bottom)
			)
		)
		(property "Value" "ESD204DQAR"
			(at 213.36 181.61 90)
			(effects
				(font
					(size 1.27 1.27)
					(thickness 0.15)
				)
				(justify left bottom)
				(hide yes)
			)
		)
		(property "Footprint" "antmicro-footprints:USON-10_2.5x1mm_P0.5mm"
			(at 223.52 194.31 0)
			(effects
				(font
					(size 1.27 1.27)
					(thickness 0.15)
				)
				(justify left bottom)
				(hide yes)
			)
		)
		(property "Datasheet" "https://www.ti.com/lit/ds/symlink/esd204.pdf?ts=1706004844383&ref_url=https%253A%252F%252Fwww.ti.com%252Finterface%252Fdiodes%252Fesd-protection-diodes%252Fproducts.html"
			(at 220.98 194.31 0)
			(effects
				(font
					(size 1.27 1.27)
					(thickness 0.15)
				)
				(justify left bottom)
				(hide yes)
			)
		)
		(property "Description" ""
			(at 228.6 170.18 0)
			(effects
				(font
					(size 1.27 1.27)
				)
				(hide yes)
			)
		)
		(property "Manufacturer" "Texas Instruments"
			(at 218.44 194.31 0)
			(effects
				(font
					(size 1.27 1.27)
					(thickness 0.15)
				)
				(justify left bottom)
				(hide yes)
			)
		)
		(property "MPN" "ESD204DQAR"
			(at 217.17 184.15 90)
			(effects
				(font
					(size 1.27 1.27)
					(thickness 0.15)
				)
				(justify left bottom)
			)
		)
		(property "Author" "Antmicro"
			(at 213.36 194.31 0)
			(effects
				(font
					(size 1.27 1.27)
					(thickness 0.15)
				)
				(justify left bottom)
				(hide yes)
			)
		)
		(property "License" "Apache-2.0"
			(at 210.82 194.31 0)
			(effects
				(font
					(size 1.27 1.27)
					(thickness 0.15)
				)
				(justify left bottom)
				(hide yes)
			)
		)
		(pin "1"
		)
		(pin "10"
		)
		(pin "2"
		)
		(pin "3"
		)
		(pin "4"
		)
		(pin "5"
		)
		(pin "6"
		)
		(pin "7"
		)
		(pin "8"
		)
		(pin "9"
		)
		(instances
			(project "com-express-7-baseboard"
				(path ""
					(reference "U47")
					(unit 1)
				)
			)
		)
	)
)
